# T6G (Grand Teton) — schematic netlist excerpt (pin names and nets, part order shuffled) for the footprints in the layout excerpt that follows; sources: Cadence DE-HDL packaged netlist, KiCad conversion of 04192023_DAF0TMB3IC0_F0TG_MB_C_brd_V02_OCP.brd

R1500  Q_RES  0 5% CHIP  pkg 0402LF  page 247 : A = HP_LVC3_OCP_V3_1_R_EN ; B = P12V_OCP_SFF_BUF_EN_R
C743  Q_CAP_DIFFBUS  DIFF BUS_0.22UF 6.3V 20% X6S  pkg C0201  page 66 : \1\ = P5E_CPU1_P2_TX_C_DP<15> ; \2\ = P5E_CPU1_P2_TX_DP<15>
PC2233  Q_CAP  1UF 25V 10% X6S  pkg C0402  page 152 : A = P12V_SCM_VCC ; B = GND

(kicad_pcb
	(version 20260206)
	(generator "pcbnew")
	(generator_version "10.0")
	(general
		(thickness 1.6)
		(legacy_teardrops no)
	)
	(paper "A4")
	(title_block
		(title "04192023_DAF0TMB3IC0_F0TG_MB_C_brd_V02_OCP.brd")
		(comment 1 "Grand Teton / footprints 2467-2469 of 8354")
	)
	(layers
		(0 "F.Cu" signal "TOP")
		(4 "In1.Cu" signal "GND")
		(6 "In2.Cu" signal "IN1")
		(8 "In3.Cu" signal "GND1")
		(10 "In4.Cu" signal "IN2")
		(12 "In5.Cu" signal "GND2")
		(14 "In6.Cu" signal "IN3")
		(16 "In7.Cu" signal "GND3")
		(18 "In8.Cu" signal "VCC")
		(20 "In9.Cu" signal "VCC1")
		(22 "In10.Cu" signal "GND4")
		(24 "In11.Cu" signal "IN4")
		(26 "In12.Cu" signal "GND5")
		(28 "In13.Cu" signal "IN5")
		(30 "In14.Cu" signal "GND6")
		(32 "In15.Cu" signal "IN6")
		(34 "In16.Cu" signal "GND7")
		(2 "B.Cu" signal "BOTTOM")
		(9 "F.Adhes" user "F.Adhesive")
		(11 "B.Adhes" user "B.Adhesive")
		(13 "F.Paste" user "Package Geometry/Pastemask Top")
		(15 "B.Paste" user "Package Geometry/Pastemask Bottom")
		(5 "F.SilkS" user "Ref Des/Silkscreen Top")
		(7 "B.SilkS" user "Ref Des/Silkscreen Bottom")
		(1 "F.Mask" user "Board Geometry/Soldermask Top")
		(3 "B.Mask" user "Board Geometry/Soldermask Bottom")
		(17 "Dwgs.User" user "User.Drawings")
		(19 "Cmts.User" user "User.Comments")
		(21 "Eco1.User" user "User.Eco1")
		(23 "Eco2.User" user "User.Eco2")
		(25 "Edge.Cuts" user "Board Geometry/Outline")
		(27 "Margin" user)
		(31 "F.CrtYd" user "Package Geometry/Place Bound Top")
		(29 "B.CrtYd" user "Package Geometry/Place Bound Bottom")
		(35 "F.Fab" user "Ref Des/Assembly Top")
		(33 "B.Fab" user "Ref Des/Assembly Bottom")
	)
	(footprint ""
		(layer "F.Cu")
		(at 187.892182 -28.258008 180)
		(property "Reference" "PC2233"
			(at 0 0 180)
			(layer "F.SilkS")
			(hide yes)
			(effects
				(font
					(size 1.27 1.27)
				)
			)
		)
		(property "Value" ""
			(at 0 0 180)
			(layer "F.Fab")
			(effects
				(font
					(size 1.27 1.27)
				)
			)
		)
		(duplicate_pad_numbers_are_jumpers no)
		(fp_line
			(start 0.7874 0.4064)
			(end -0.7874 0.4064)
			(stroke
				(width 0.1524)
				(type default)
			)
			(layer "F.SilkS")
		)
		(fp_line
			(start 0.7874 -0.4064)
			(end 0.7874 0.4064)
			(stroke
				(width 0.1524)
				(type default)
			)
			(layer "F.SilkS")
		)
		(fp_line
			(start -0.7874 0.4064)
			(end -0.7874 -0.4064)
			(stroke
				(width 0.1524)
				(type default)
			)
			(layer "F.SilkS")
		)
		(fp_line
			(start -0.7874 -0.4064)
			(end 0.7874 -0.4064)
			(stroke
				(width 0.1524)
				(type default)
			)
			(layer "F.SilkS")
		)
		(fp_line
			(start 0.67945 0.3048)
			(end 0.120396 0.3048)
			(stroke
				(width 0.1)
				(type default)
			)
			(layer "F.Fab")
		)
		(fp_line
			(start 0.67945 -0.3048)
			(end 0.67945 0.3048)
			(stroke
				(width 0.1)
				(type default)
			)
			(layer "F.Fab")
		)
		(fp_line
			(start 0.12065 -0.2794)
			(end 0.12065 -0.3048)
			(stroke
				(width 0.1)
				(type default)
			)
			(layer "F.Fab")
		)
		(fp_line
			(start 0.12065 -0.3048)
			(end 0.67945 -0.3048)
			(stroke
				(width 0.1)
				(type default)
			)
			(layer "F.Fab")
		)
		(fp_line
			(start 0.120396 0.3048)
			(end 0.120396 0.2794)
			(stroke
				(width 0.1)
				(type default)
			)
			(layer "F.Fab")
		)
		(fp_line
			(start 0.120396 0.2794)
			(end -0.12065 0.2794)
			(stroke
				(width 0.1)
				(type default)
			)
			(layer "F.Fab")
		)
		(fp_line
			(start -0.12065 0.3048)
			(end -0.67945 0.3048)
			(stroke
				(width 0.1)
				(type default)
			)
			(layer "F.Fab")
		)
		(fp_line
			(start -0.12065 0.2794)
			(end -0.12065 0.3048)
			(stroke
				(width 0.1)
				(type default)
			)
			(layer "F.Fab")
		)
		(fp_line
			(start -0.12065 -0.2794)
			(end 0.12065 -0.2794)
			(stroke
				(width 0.1)
				(type default)
			)
			(layer "F.Fab")
		)
		(fp_line
			(start -0.12065 -0.305054)
			(end -0.12065 -0.2794)
			(stroke
				(width 0.1)
				(type default)
			)
			(layer "F.Fab")
		)
		(fp_line
			(start -0.67945 0.3048)
			(end -0.67945 -0.305054)
			(stroke
				(width 0.1)
				(type default)
			)
			(layer "F.Fab")
		)
		(fp_line
			(start -0.67945 -0.305054)
			(end -0.12065 -0.305054)
			(stroke
				(width 0.1)
				(type default)
			)
			(layer "F.Fab")
		)
		(pad "1" smd circle
			(at -0.40005 0 180)
			(size 0 0)
			(layers "F.Cu" "F.Mask" "F.Paste")
			(net "P12V_SCM_VCC")
		)
		(pad "2" smd circle
			(at 0.40005 0 180)
			(size 0 0)
			(layers "F.Cu" "F.Mask" "F.Paste")
			(net "GND")
		)
	)
	(footprint ""
		(layer "F.Cu")
		(at 412.481268 -70.74408)
		(property "Reference" "R1500"
			(at 0 0 0)
			(layer "F.SilkS")
			(hide yes)
			(effects
				(font
					(size 1.27 1.27)
				)
			)
		)
		(property "Value" ""
			(at 0 0 0)
			(layer "F.Fab")
			(effects
				(font
					(size 1.27 1.27)
				)
			)
		)
		(duplicate_pad_numbers_are_jumpers no)
		(fp_line
			(start -0.7874 -0.4064)
			(end 0.7874 -0.4064)
			(stroke
				(width 0.1524)
				(type default)
			)
			(layer "F.SilkS")
		)
		(fp_line
			(start -0.7874 0.4064)
			(end -0.7874 -0.4064)
			(stroke
				(width 0.1524)
				(type default)
			)
			(layer "F.SilkS")
		)
		(fp_line
			(start 0.7874 -0.4064)
			(end 0.7874 0.4064)
			(stroke
				(width 0.1524)
				(type default)
			)
			(layer "F.SilkS")
		)
		(fp_line
			(start 0.7874 0.4064)
			(end -0.7874 0.4064)
			(stroke
				(width 0.1524)
				(type default)
			)
			(layer "F.SilkS")
		)
		(fp_line
			(start -0.67945 -0.305054)
			(end -0.12065 -0.305054)
			(stroke
				(width 0.1)
				(type default)
			)
			(layer "F.Fab")
		)
		(fp_line
			(start -0.67945 0.3048)
			(end -0.67945 -0.305054)
			(stroke
				(width 0.1)
				(type default)
			)
			(layer "F.Fab")
		)
		(fp_line
			(start -0.12065 -0.305054)
			(end -0.12065 -0.2794)
			(stroke
				(width 0.1)
				(type default)
			)
			(layer "F.Fab")
		)
		(fp_line
			(start -0.12065 -0.2794)
			(end 0.12065 -0.2794)
			(stroke
				(width 0.1)
				(type default)
			)
			(layer "F.Fab")
		)
		(fp_line
			(start -0.12065 0.2794)
			(end -0.12065 0.3048)
			(stroke
				(width 0.1)
				(type default)
			)
			(layer "F.Fab")
		)
		(fp_line
			(start -0.12065 0.3048)
			(end -0.67945 0.3048)
			(stroke
				(width 0.1)
				(type default)
			)
			(layer "F.Fab")
		)
		(fp_line
			(start 0.120396 0.2794)
			(end -0.12065 0.2794)
			(stroke
				(width 0.1)
				(type default)
			)
			(layer "F.Fab")
		)
		(fp_line
			(start 0.120396 0.3048)
			(end 0.120396 0.2794)
			(stroke
				(width 0.1)
				(type default)
			)
			(layer "F.Fab")
		)
		(fp_line
			(start 0.12065 -0.3048)
			(end 0.67945 -0.3048)
			(stroke
				(width 0.1)
				(type default)
			)
			(layer "F.Fab")
		)
		(fp_line
			(start 0.12065 -0.2794)
			(end 0.12065 -0.3048)
			(stroke
				(width 0.1)
				(type default)
			)
			(layer "F.Fab")
		)
		(fp_line
			(start 0.67945 -0.3048)
			(end 0.67945 0.3048)
			(stroke
				(width 0.1)
				(type default)
			)
			(layer "F.Fab")
		)
		(fp_line
			(start 0.67945 0.3048)
			(end 0.120396 0.3048)
			(stroke
				(width 0.1)
				(type default)
			)
			(layer "F.Fab")
		)
		(pad "1" smd circle
			(at -0.40005 0)
			(size 0 0)
			(layers "F.Cu" "F.Mask" "F.Paste")
			(net "HP_LVC3_OCP_V3_1_R_EN")
		)
		(pad "2" smd circle
			(at 0.40005 0)
			(size 0 0)
			(layers "F.Cu" "F.Mask" "F.Paste")
			(net "P12V_OCP_SFF_BUF_EN_R")
		)
	)
	(footprint ""
		(layer "F.Cu")
		(at 169.368724 -379.471428)
		(property "Reference" "C743"
			(at 0 0 0)
			(layer "F.SilkS")
			(hide yes)
			(effects
				(font
					(size 1.27 1.27)
				)
			)
		)
		(property "Value" ""
			(at 0 0 0)
			(layer "F.Fab")
			(effects
				(font
					(size 1.27 1.27)
				)
			)
		)
		(duplicate_pad_numbers_are_jumpers no)
		(fp_line
			(start -0.299974 -0.150114)
			(end 0.299974 -0.150114)
			(stroke
				(width 0.1)
				(type default)
			)
			(layer "F.Fab")
		)
		(fp_line
			(start -0.299974 0.150114)
			(end -0.299974 -0.150114)
			(stroke
				(width 0.1)
				(type default)
			)
			(layer "F.Fab")
		)
		(fp_line
			(start 0.299974 -0.150114)
			(end 0.299974 0.150114)
			(stroke
				(width 0.1)
				(type default)
			)
			(layer "F.Fab")
		)
		(fp_line
			(start 0.299974 0.150114)
			(end -0.299974 0.150114)
			(stroke
				(width 0.1)
				(type default)
			)
			(layer "F.Fab")
		)
		(pad "1" smd rect
			(at -0.2667 0)
			(size 0.3048 0.381)
			(layers "F.Cu" "F.Mask" "F.Paste")
			(net "P5E_CPU1_P2_TX_C_DP<15>")
		)
		(pad "2" smd rect
			(at 0.2667 0)
			(size 0.3048 0.381)
			(layers "F.Cu" "F.Mask" "F.Paste")
			(net "P5E_CPU1_P2_TX_DP<15>")
		)
	)
)
